(kicad_pcb
	(version 20260206)
	(generator "pcbnew")
	(generator_version "10.0")
	(general
		(thickness 1.6)
		(legacy_teardrops no)
	)
	(paper "A4")
	(title_block
		(title "fcb — Lightning_FCB_BRD.brd")
		(comment 1 "Lightning (Wiwynn / Facebook NVMe JBOF) / footprints 161-166 of 495")
	)
	(layers
		(0 "F.Cu" signal "TOP")
		(4 "In1.Cu" signal "L2GND")
		(6 "In2.Cu" signal "L3VCC")
		(2 "B.Cu" signal "BOTTOM")
		(9 "F.Adhes" user "F.Adhesive")
		(11 "B.Adhes" user "B.Adhesive")
		(13 "F.Paste" user "Package Geometry/Pastemask Top")
		(15 "B.Paste" user "Package Geometry/Pastemask Bottom")
		(5 "F.SilkS" user "Ref Des/Silkscreen Top")
		(7 "B.SilkS" user "Ref Des/Silkscreen Bottom")
		(1 "F.Mask" user "Board Geometry/Soldermask Top")
		(3 "B.Mask" user "Board Geometry/Soldermask Bottom")
		(17 "Dwgs.User" user "User.Drawings")
		(19 "Cmts.User" user "User.Comments")
		(21 "Eco1.User" user "User.Eco1")
		(23 "Eco2.User" user "User.Eco2")
		(25 "Edge.Cuts" user "Board Geometry/Outline")
		(27 "Margin" user)
		(31 "F.CrtYd" user "Package Geometry/Place Bound Top")
		(29 "B.CrtYd" user "Package Geometry/Place Bound Bottom")
		(35 "F.Fab" user "Ref Des/Assembly Top")
		(33 "B.Fab" user "Ref Des/Assembly Bottom")
	)
	(footprint ""
		(layer "F.Cu")
		(at 27.500072 -320.000122 90)
		(property "Reference" "Q2"
			(at 0 0 90)
			(layer "F.SilkS")
			(hide yes)
			(effects
				(font
					(size 1.27 1.27)
				)
			)
		)
		(property "Value" "PMBS3904-1-GP"
			(at 0 -9.0932 90)
			(unlocked yes)
			(layer "F.Fab")
			(hide yes)
			(effects
				(font
					(size 1.016 1.016)
					(thickness 0.1524)
				)
			)
		)
		(property "Device Type" "SOT-23-10H44"
			(at 0 -10.6172 90)
			(unlocked yes)
			(layer "F.Fab")
			(hide yes)
			(effects
				(font
					(size 1.016 1.016)
					(thickness 0.1524)
				)
			)
		)
		(duplicate_pad_numbers_are_jumpers no)
		(fp_line
			(start 1.651 -1.778)
			(end -1.651 -1.778)
			(stroke
				(width 0.1524)
				(type default)
			)
			(layer "F.SilkS")
		)
		(fp_line
			(start -1.651 -1.778)
			(end -1.651 1.778)
			(stroke
				(width 0.1524)
				(type default)
			)
			(layer "F.SilkS")
		)
		(fp_line
			(start 1.651 1.778)
			(end 1.651 -1.778)
			(stroke
				(width 0.1524)
				(type default)
			)
			(layer "F.SilkS")
		)
		(fp_line
			(start -1.651 1.778)
			(end 1.651 1.778)
			(stroke
				(width 0.1524)
				(type default)
			)
			(layer "F.SilkS")
		)
		(fp_line
			(start -0.9906 1.86309)
			(end -0.701294 2.15265)
			(stroke
				(width 0.0127)
				(type default)
			)
			(layer "F.SilkS")
		)
		(fp_line
			(start -0.994156 1.8669)
			(end -0.987044 1.8669)
			(stroke
				(width 0.0127)
				(type default)
			)
			(layer "F.SilkS")
		)
		(fp_line
			(start -1.003808 1.876552)
			(end -0.977646 1.876552)
			(stroke
				(width 0.0127)
				(type default)
			)
			(layer "F.SilkS")
		)
		(fp_line
			(start -0.635 1.8796)
			(end -1.7526 1.8796)
			(stroke
				(width 0.3302)
				(type default)
			)
			(layer "F.SilkS")
		)
		(fp_line
			(start -1.7526 1.8796)
			(end -1.7526 0.9906)
			(stroke
				(width 0.3302)
				(type default)
			)
			(layer "F.SilkS")
		)
		(fp_line
			(start -1.013206 1.88595)
			(end -0.967994 1.88595)
			(stroke
				(width 0.0127)
				(type default)
			)
			(layer "F.SilkS")
		)
		(fp_line
			(start -1.022858 1.895602)
			(end -0.958596 1.895602)
			(stroke
				(width 0.0127)
				(type default)
			)
			(layer "F.SilkS")
		)
		(fp_line
			(start -1.032256 1.905)
			(end -0.948944 1.905)
			(stroke
				(width 0.0127)
				(type default)
			)
			(layer "F.SilkS")
		)
		(fp_line
			(start -1.041908 1.914652)
			(end -0.939546 1.914652)
			(stroke
				(width 0.0127)
				(type default)
			)
			(layer "F.SilkS")
		)
		(fp_line
			(start -1.051306 1.92405)
			(end -0.929894 1.92405)
			(stroke
				(width 0.0127)
				(type default)
			)
			(layer "F.SilkS")
		)
		(fp_line
			(start -1.060958 1.933702)
			(end -0.920496 1.933702)
			(stroke
				(width 0.0127)
				(type default)
			)
			(layer "F.SilkS")
		)
		(fp_line
			(start -1.070356 1.9431)
			(end -0.910844 1.9431)
			(stroke
				(width 0.0127)
				(type default)
			)
			(layer "F.SilkS")
		)
		(fp_line
			(start -1.080008 1.952752)
			(end -0.901446 1.952752)
			(stroke
				(width 0.0127)
				(type default)
			)
			(layer "F.SilkS")
		)
		(fp_line
			(start -1.089406 1.96215)
			(end -0.891794 1.96215)
			(stroke
				(width 0.0127)
				(type default)
			)
			(layer "F.SilkS")
		)
		(fp_line
			(start -1.099058 1.971802)
			(end -0.882396 1.971802)
			(stroke
				(width 0.0127)
				(type default)
			)
			(layer "F.SilkS")
		)
		(fp_line
			(start -1.108456 1.9812)
			(end -0.872744 1.9812)
			(stroke
				(width 0.0127)
				(type default)
			)
			(layer "F.SilkS")
		)
		(fp_line
			(start -1.118108 1.990852)
			(end -0.863346 1.990852)
			(stroke
				(width 0.0127)
				(type default)
			)
			(layer "F.SilkS")
		)
		(fp_line
			(start -1.127506 2.00025)
			(end -0.853694 2.00025)
			(stroke
				(width 0.0127)
				(type default)
			)
			(layer "F.SilkS")
		)
		(fp_line
			(start -1.137158 2.009902)
			(end -0.844296 2.009902)
			(stroke
				(width 0.0127)
				(type default)
			)
			(layer "F.SilkS")
		)
		(fp_line
			(start -1.146556 2.0193)
			(end -0.834644 2.0193)
			(stroke
				(width 0.0127)
				(type default)
			)
			(layer "F.SilkS")
		)
		(fp_line
			(start -1.156208 2.028952)
			(end -0.825246 2.028952)
			(stroke
				(width 0.0127)
				(type default)
			)
			(layer "F.SilkS")
		)
		(fp_line
			(start -1.165606 2.03835)
			(end -0.815594 2.03835)
			(stroke
				(width 0.0127)
				(type default)
			)
			(layer "F.SilkS")
		)
		(fp_line
			(start -1.175258 2.048002)
			(end -0.806196 2.048002)
			(stroke
				(width 0.0127)
				(type default)
			)
			(layer "F.SilkS")
		)
		(fp_line
			(start -1.184656 2.0574)
			(end -0.796544 2.0574)
			(stroke
				(width 0.0127)
				(type default)
			)
			(layer "F.SilkS")
		)
		(fp_line
			(start -1.194308 2.067052)
			(end -0.787146 2.067052)
			(stroke
				(width 0.0127)
				(type default)
			)
			(layer "F.SilkS")
		)
		(fp_line
			(start -1.203706 2.07645)
			(end -0.777494 2.07645)
			(stroke
				(width 0.0127)
				(type default)
			)
			(layer "F.SilkS")
		)
		(fp_line
			(start -1.213358 2.086102)
			(end -0.768096 2.086102)
			(stroke
				(width 0.0127)
				(type default)
			)
			(layer "F.SilkS")
		)
		(fp_line
			(start -1.222756 2.0955)
			(end -0.758444 2.0955)
			(stroke
				(width 0.0127)
				(type default)
			)
			(layer "F.SilkS")
		)
		(fp_line
			(start -1.232408 2.105152)
			(end -0.749046 2.105152)
			(stroke
				(width 0.0127)
				(type default)
			)
			(layer "F.SilkS")
		)
		(fp_line
			(start -1.241806 2.11455)
			(end -0.739394 2.11455)
			(stroke
				(width 0.0127)
				(type default)
			)
			(layer "F.SilkS")
		)
		(fp_line
			(start -1.251458 2.124202)
			(end -0.729996 2.124202)
			(stroke
				(width 0.0127)
				(type default)
			)
			(layer "F.SilkS")
		)
		(fp_line
			(start -1.260856 2.1336)
			(end -0.720344 2.1336)
			(stroke
				(width 0.0127)
				(type default)
			)
			(layer "F.SilkS")
		)
		(fp_line
			(start -0.719074 2.145538)
			(end -1.265936 2.14122)
			(stroke
				(width 0.0127)
				(type default)
			)
			(layer "F.SilkS")
		)
		(fp_line
			(start -1.279398 2.152142)
			(end -0.9906 1.86309)
			(stroke
				(width 0.0127)
				(type default)
			)
			(layer "F.SilkS")
		)
		(fp_line
			(start -0.71628 2.15265)
			(end -1.26492 2.15265)
			(stroke
				(width 0.0127)
				(type default)
			)
			(layer "F.SilkS")
		)
		(fp_line
			(start -1.279144 2.15265)
			(end -0.701294 2.15265)
			(stroke
				(width 0.0127)
				(type default)
			)
			(layer "F.SilkS")
		)
		(fp_poly
			(pts
				(xy -1.285748 2.159) (xy -1.285748 1.8796) (xy -1.778 1.8796) (xy -1.778 -1.8796) (xy 1.778 -1.8796)
				(xy 1.778 1.8796) (xy -0.694944 1.8796) (xy -0.694944 2.159)
			)
			(stroke
				(width 0)
				(type default)
			)
			(fill no)
			(layer "F.CrtYd")
		)
		(fp_poly
			(pts
				(xy -1.285748 2.159) (xy -1.285748 1.8796) (xy -1.778 1.8796) (xy -1.778 -1.8796) (xy 1.778 -1.8796)
				(xy 1.778 1.8796) (xy -0.694944 1.8796) (xy -0.694944 2.159)
			)
			(stroke
				(width 0)
				(type default)
			)
			(fill no)
			(layer "F.Fab")
		)
		(pad "1" smd rect
			(at -0.98425 0.9525 90)
			(size 0.762 1.143)
			(layers "F.Cu" "F.Mask" "F.Paste")
			(net "NCT7904_D2+")
		)
		(pad "2" smd rect
			(at 0.98425 0.9525 90)
			(size 0.762 1.143)
			(layers "F.Cu" "F.Mask" "F.Paste")
			(net "NCT7904_D2-")
		)
		(pad "3" smd rect
			(at 0 -0.9525 90)
			(size 0.762 1.143)
			(layers "F.Cu" "F.Mask" "F.Paste")
			(net "NCT7904_D2+")
		)
	)
	(footprint ""
		(layer "F.Cu")
		(at 47.625 -408.051 90)
		(property "Reference" "PC7"
			(at 0 0 90)
			(layer "F.SilkS")
			(hide yes)
			(effects
				(font
					(size 1.27 1.27)
				)
			)
		)
		(property "Value" "SC1U25V5KX-1GP"
			(at -0.0762 -6.1214 90)
			(unlocked yes)
			(layer "F.Fab")
			(hide yes)
			(effects
				(font
					(size 1.016 1.016)
					(thickness 0.1524)
				)
			)
		)
		(property "Device Type" "C805H58"
			(at -0.0762 -8.1534 90)
			(unlocked yes)
			(layer "F.Fab")
			(hide yes)
			(effects
				(font
					(size 1.016 1.016)
					(thickness 0.1524)
				)
			)
		)
		(duplicate_pad_numbers_are_jumpers no)
		(fp_line
			(start 0.635 0)
			(end -0.635 0)
			(stroke
				(width 0.508)
				(type default)
			)
			(layer "F.SilkS")
		)
		(fp_rect
			(start -0.9652 1.778)
			(end 0.9652 -1.778)
			(stroke
				(width 0)
				(type default)
			)
			(fill no)
			(layer "F.CrtYd")
		)
		(fp_poly
			(pts
				(xy -0.9652 -1.778) (xy 0.9652 -1.778) (xy 0.9652 1.778) (xy -0.9652 1.778)
			)
			(stroke
				(width 0)
				(type default)
			)
			(fill no)
			(layer "F.Fab")
		)
		(pad "1" smd rect
			(at 0 -0.9652 90)
			(size 1.397 1.143)
			(layers "F.Cu" "F.Mask" "F.Paste")
			(net "P12V_SENSE_TRACE")
		)
		(pad "2" smd rect
			(at 0 0.9652 90)
			(size 1.397 1.143)
			(layers "F.Cu" "F.Mask" "F.Paste")
			(net "GND")
		)
	)
	(footprint ""
		(layer "F.Cu")
		(at 21.844508 -192.505838)
		(property "Reference" "F3"
			(at 0 0 0)
			(layer "F.SilkS")
			(hide yes)
			(effects
				(font
					(size 1.27 1.27)
				)
			)
		)
		(property "Value" "FUSE-3A15V-GP"
			(at 0.2286 -10.5918 0)
			(unlocked yes)
			(layer "F.Fab")
			(hide yes)
			(effects
				(font
					(size 1.016 1.016)
					(thickness 0.1524)
				)
			)
		)
		(property "Device Type" "FUSE-7452-UH50"
			(at 0.2286 -12.4968 0)
			(unlocked yes)
			(layer "F.Fab")
			(hide yes)
			(effects
				(font
					(size 1.016 1.016)
					(thickness 0.1524)
				)
			)
		)
		(duplicate_pad_numbers_are_jumpers no)
		(fp_line
			(start -4.9276 -2.921)
			(end 4.9276 -2.921)
			(stroke
				(width 0.1524)
				(type default)
			)
			(layer "F.SilkS")
		)
		(fp_line
			(start -4.9276 2.921)
			(end -4.9276 -2.921)
			(stroke
				(width 0.1524)
				(type default)
			)
			(layer "F.SilkS")
		)
		(fp_line
			(start 4.9276 -2.921)
			(end 4.9276 2.921)
			(stroke
				(width 0.1524)
				(type default)
			)
			(layer "F.SilkS")
		)
		(fp_line
			(start 4.9276 2.921)
			(end -4.9276 2.921)
			(stroke
				(width 0.1524)
				(type default)
			)
			(layer "F.SilkS")
		)
		(fp_poly
			(pts
				(xy -5.08 3.0988) (xy 5.08 3.0988) (xy 5.08 -3.0988) (xy -5.08 -3.0988)
			)
			(stroke
				(width 0)
				(type default)
			)
			(fill no)
			(layer "F.CrtYd")
		)
		(fp_poly
			(pts
				(xy -5.08 -3.0988) (xy 5.08 -3.0988) (xy 5.08 3.0988) (xy -5.08 3.0988)
			)
			(stroke
				(width 0)
				(type default)
			)
			(fill no)
			(layer "F.Fab")
		)
		(pad "1" smd rect
			(at -3.4036 0)
			(size 2.2098 5.2832)
			(layers "F.Cu" "F.Mask" "F.Paste")
			(net "P12V_FAN4")
		)
		(pad "2" smd rect
			(at 3.4036 0)
			(size 2.2098 5.2832)
			(layers "F.Cu" "F.Mask" "F.Paste")
			(net "P12V")
		)
	)
	(footprint ""
		(layer "F.Cu")
		(at 25.018238 -481.735892 -90)
		(property "Reference" "F6"
			(at 0 0 270)
			(layer "F.SilkS")
			(hide yes)
			(effects
				(font
					(size 1.27 1.27)
				)
			)
		)
		(property "Value" "FUSE-3A15V-GP"
			(at 0.2286 -10.5918 270)
			(unlocked yes)
			(layer "F.Fab")
			(hide yes)
			(effects
				(font
					(size 1.016 1.016)
					(thickness 0.1524)
				)
			)
		)
		(property "Device Type" "FUSE-7452-UH50"
			(at 0.2286 -12.4968 270)
			(unlocked yes)
			(layer "F.Fab")
			(hide yes)
			(effects
				(font
					(size 1.016 1.016)
					(thickness 0.1524)
				)
			)
		)
		(duplicate_pad_numbers_are_jumpers no)
		(fp_line
			(start -4.9276 2.921)
			(end -4.9276 -2.921)
			(stroke
				(width 0.1524)
				(type default)
			)
			(layer "F.SilkS")
		)
		(fp_line
			(start 4.9276 2.921)
			(end -4.9276 2.921)
			(stroke
				(width 0.1524)
				(type default)
			)
			(layer "F.SilkS")
		)
		(fp_line
			(start -4.9276 -2.921)
			(end 4.9276 -2.921)
			(stroke
				(width 0.1524)
				(type default)
			)
			(layer "F.SilkS")
		)
		(fp_line
			(start 4.9276 -2.921)
			(end 4.9276 2.921)
			(stroke
				(width 0.1524)
				(type default)
			)
			(layer "F.SilkS")
		)
		(fp_poly
			(pts
				(xy -5.08 3.0988) (xy 5.08 3.0988) (xy 5.08 -3.0988) (xy -5.08 -3.0988)
			)
			(stroke
				(width 0)
				(type default)
			)
			(fill no)
			(layer "F.CrtYd")
		)
		(fp_poly
			(pts
				(xy -5.08 -3.0988) (xy 5.08 -3.0988) (xy 5.08 3.0988) (xy -5.08 3.0988)
			)
			(stroke
				(width 0)
				(type default)
			)
			(fill no)
			(layer "F.Fab")
		)
		(pad "1" smd rect
			(at -3.4036 0 270)
			(size 2.2098 5.2832)
			(layers "F.Cu" "F.Mask" "F.Paste")
			(net "P12V_FAN1")
		)
		(pad "2" smd rect
			(at 3.4036 0 270)
			(size 2.2098 5.2832)
			(layers "F.Cu" "F.Mask" "F.Paste")
			(net "P12V")
		)
	)
	(footprint ""
		(layer "F.Cu")
		(at 39.243 -174.117)
		(property "Reference" "PR44"
			(at 0 0 0)
			(layer "F.SilkS")
			(hide yes)
			(effects
				(font
					(size 1.27 1.27)
				)
			)
		)
		(property "Value" "1KR2F-3-GP"
			(at 0.064008 -3.993896 0)
			(unlocked yes)
			(layer "F.Fab")
			(hide yes)
			(effects
				(font
					(size 1.016 1.016)
					(thickness 0.1524)
				)
			)
		)
		(property "Device Type" "R402H16"
			(at 0.064008 -5.517896 0)
			(unlocked yes)
			(layer "F.Fab")
			(hide yes)
			(effects
				(font
					(size 1.016 1.016)
					(thickness 0.1524)
				)
			)
		)
		(duplicate_pad_numbers_are_jumpers no)
		(fp_line
			(start -0.508 -0.9398)
			(end -0.508 0.9398)
			(stroke
				(width 0.1524)
				(type default)
			)
			(layer "F.SilkS")
		)
		(fp_line
			(start 0.508 -0.9398)
			(end -0.508 -0.9398)
			(stroke
				(width 0.1524)
				(type default)
			)
			(layer "F.SilkS")
		)
		(fp_rect
			(start -0.508 0.9398)
			(end 0.508 -0.9398)
			(stroke
				(width 0)
				(type default)
			)
			(fill no)
			(layer "F.CrtYd")
		)
		(fp_rect
			(start -0.508 0.9398)
			(end 0.508 -0.9398)
			(stroke
				(width 0)
				(type default)
			)
			(fill no)
			(layer "F.Fab")
		)
		(pad "1" smd custom
			(at 0 -0.4445)
			(size 0.1397 0.1397)
			(layers "F.Cu" "F.Mask" "F.Paste")
			(net "TEMP_ALM#")
			(options
				(clearance outline)
				(anchor circle)
			)
			(primitives
				(gr_poly
					(pts
						(arc
							(start -0.1778 -0.2794)
							(mid -0.249642 -0.249642)
							(end -0.2794 -0.1778)
						)
						(arc
							(start -0.2794 0.1778)
							(mid -0.249642 0.249642)
							(end -0.1778 0.2794)
						)
						(arc
							(start 0.1778 0.2794)
							(mid 0.249642 0.249642)
							(end 0.2794 0.1778)
						)
						(arc
							(start 0.2794 -0.1778)
							(mid 0.249642 -0.249642)
							(end 0.1778 -0.2794)
						)
					)
					(width 0)
					(fill yes)
				)
			)
		)
		(pad "2" smd custom
			(at 0 0.4445)
			(size 0.1397 0.1397)
			(layers "F.Cu" "F.Mask" "F.Paste")
			(net "TEMP_ALM#_IN")
			(options
				(clearance outline)
				(anchor circle)
			)
			(primitives
				(gr_poly
					(pts
						(arc
							(start -0.1778 -0.2794)
							(mid -0.249642 -0.249642)
							(end -0.2794 -0.1778)
						)
						(arc
							(start -0.2794 0.1778)
							(mid -0.249642 0.249642)
							(end -0.1778 0.2794)
						)
						(arc
							(start 0.1778 0.2794)
							(mid 0.249642 0.249642)
							(end 0.2794 0.1778)
						)
						(arc
							(start 0.2794 -0.1778)
							(mid 0.249642 -0.249642)
							(end 0.1778 -0.2794)
						)
					)
					(width 0)
					(fill yes)
				)
			)
		)
	)
	(footprint ""
		(layer "F.Cu")
		(at 41.7576 -158.1658 90)
		(property "Reference" "R50"
			(at 0 0 90)
			(layer "F.SilkS")
			(hide yes)
			(effects
				(font
					(size 1.27 1.27)
				)
			)
		)
		(property "Value" "0R2J-2-GP"
			(at 0.064008 -3.993896 90)
			(unlocked yes)
			(layer "F.Fab")
			(hide yes)
			(effects
				(font
					(size 1.016 1.016)
					(thickness 0.1524)
				)
			)
		)
		(property "Device Type" "R402H16"
			(at 0.064008 -5.517896 90)
			(unlocked yes)
			(layer "F.Fab")
			(hide yes)
			(effects
				(font
					(size 1.016 1.016)
					(thickness 0.1524)
				)
			)
		)
		(duplicate_pad_numbers_are_jumpers no)
		(fp_line
			(start 0.508 -0.9398)
			(end -0.508 -0.9398)
			(stroke
				(width 0.1524)
				(type default)
			)
			(layer "F.SilkS")
		)
		(fp_line
			(start -0.508 -0.9398)
			(end -0.508 0.9398)
			(stroke
				(width 0.1524)
				(type default)
			)
			(layer "F.SilkS")
		)
		(fp_rect
			(start -0.508 0.9398)
			(end 0.508 -0.9398)
			(stroke
				(width 0)
				(type default)
			)
			(fill no)
			(layer "F.CrtYd")
		)
		(fp_rect
			(start -0.508 0.9398)
			(end 0.508 -0.9398)
			(stroke
				(width 0)
				(type default)
			)
			(fill no)
			(layer "F.Fab")
		)
		(pad "1" smd custom
			(at 0 -0.4445 90)
			(size 0.1397 0.1397)
			(layers "F.Cu" "F.Mask" "F.Paste")
			(net "NCT7904_VSEN1")
			(options
				(clearance outline)
				(anchor circle)
			)
			(primitives
				(gr_poly
					(pts
						(arc
							(start -0.1778 -0.2794)
							(mid -0.249642 -0.249642)
							(end -0.2794 -0.1778)
						)
						(arc
							(start -0.2794 0.1778)
							(mid -0.249642 0.249642)
							(end -0.1778 0.2794)
						)
						(arc
							(start 0.1778 0.2794)
							(mid 0.249642 0.249642)
							(end 0.2794 0.1778)
						)
						(arc
							(start 0.2794 -0.1778)
							(mid 0.249642 -0.249642)
							(end 0.1778 -0.2794)
						)
					)
					(width 0)
					(fill yes)
				)
			)
		)
		(pad "2" smd custom
			(at 0 0.4445 90)
			(size 0.1397 0.1397)
			(layers "F.Cu" "F.Mask" "F.Paste")
			(net "NCT7904_VSEN_P12V_AUX")
			(options
				(clearance outline)
				(anchor circle)
			)
			(primitives
				(gr_poly
					(pts
						(arc
							(start -0.1778 -0.2794)
							(mid -0.249642 -0.249642)
							(end -0.2794 -0.1778)
						)
						(arc
							(start -0.2794 0.1778)
							(mid -0.249642 0.249642)
							(end -0.1778 0.2794)
						)
						(arc
							(start 0.1778 0.2794)
							(mid 0.249642 0.249642)
							(end 0.2794 0.1778)
						)
						(arc
							(start 0.2794 -0.1778)
							(mid 0.249642 -0.249642)
							(end 0.1778 -0.2794)
						)
					)
					(width 0)
					(fill yes)
				)
			)
		)
	)
)
